(kicad_pcb
	(version 20260206)
	(generator "pcbnew")
	(generator_version "10.0")
	(general
		(thickness 1.6)
		(legacy_teardrops no)
	)
	(paper "A4")
	(title_block
		(title "timecard-production-celestica-r4006 — R4006-B0001-02_R01.brd")
		(comment 1 "Time Appliance Project (Time Card) / footprints 816-820 of 1113")
	)
	(layers
		(0 "F.Cu" signal "TOP")
		(4 "In1.Cu" signal "L02_GND1")
		(6 "In2.Cu" signal "L03_SIG1")
		(8 "In3.Cu" signal "L04_GND2")
		(10 "In4.Cu" signal "L05_VCC1")
		(12 "In5.Cu" signal "L06_VCC2")
		(14 "In6.Cu" signal "L07_GND3")
		(16 "In7.Cu" signal "L08_SIG2")
		(18 "In8.Cu" signal "L09_GND4")
		(2 "B.Cu" signal "BOTTOM")
		(9 "F.Adhes" user "F.Adhesive")
		(11 "B.Adhes" user "B.Adhesive")
		(13 "F.Paste" user "Package Geometry/Pastemask Top")
		(15 "B.Paste" user "Package Geometry/Pastemask Bottom")
		(5 "F.SilkS" user "Ref Des/Silkscreen Top")
		(7 "B.SilkS" user "Ref Des/Silkscreen Bottom")
		(1 "F.Mask" user "Board Geometry/Soldermask Top")
		(3 "B.Mask" user "Board Geometry/Soldermask Bottom")
		(17 "Dwgs.User" user "User.Drawings")
		(19 "Cmts.User" user "User.Comments")
		(21 "Eco1.User" user "User.Eco1")
		(23 "Eco2.User" user "User.Eco2")
		(25 "Edge.Cuts" user "Board Geometry/Outline")
		(27 "Margin" user)
		(31 "F.CrtYd" user "Package Geometry/Place Bound Top")
		(29 "B.CrtYd" user "Package Geometry/Place Bound Bottom")
		(35 "F.Fab" user "Ref Des/Assembly Top")
		(33 "B.Fab" user "Ref Des/Assembly Bottom")
	)
	(footprint ""
		(layer "B.Cu")
		(at 142.494 -50.292 180)
		(property "Reference" "C266"
			(at 0.254 -1.56337 0)
			(unlocked yes)
			(layer "B.SilkS")
			(effects
				(font
					(size 0.7874 0.5842)
					(thickness 0.1524)
				)
				(justify mirror)
			)
		)
		(property "Value" "VAL*"
			(at -0.0762 2.067306 180)
			(unlocked yes)
			(layer "B.Fab")
			(hide yes)
			(effects
				(font
					(size 0.7874 0.5842)
					(thickness 0.1524)
				)
				(justify mirror)
			)
		)
		(property "Device Type" "CAPACITOR-G105-0A102-FJ,1000PFA"
			(at -0.0508 1.127506 180)
			(unlocked yes)
			(layer "B.Fab")
			(hide yes)
			(effects
				(font
					(size 0.7874 0.5842)
					(thickness 0.1524)
				)
				(justify mirror)
			)
		)
		(property "User Part Number" "PARTNUM*"
			(at -0.1016 4.023106 180)
			(unlocked yes)
			(layer "Cmts.User")
			(hide yes)
			(effects
				(font
					(size 0.7874 0.5842)
					(thickness 0.1524)
				)
				(justify mirror)
			)
		)
		(property "Tolerance" "TOL*"
			(at -0.0762 3.032506 180)
			(unlocked yes)
			(layer "Cmts.User")
			(hide yes)
			(effects
				(font
					(size 0.7874 0.5842)
					(thickness 0.1524)
				)
				(justify mirror)
			)
		)
		(duplicate_pad_numbers_are_jumpers no)
		(fp_line
			(start 1.143 0.5588)
			(end -1.143 0.5588)
			(stroke
				(width 0.1)
				(type default)
			)
			(layer "B.SilkS")
		)
		(fp_line
			(start 1.143 -0.5588)
			(end 1.143 0.5588)
			(stroke
				(width 0.1)
				(type default)
			)
			(layer "B.SilkS")
		)
		(fp_line
			(start -1.143 0.5588)
			(end -1.143 -0.5588)
			(stroke
				(width 0.1)
				(type default)
			)
			(layer "B.SilkS")
		)
		(fp_line
			(start -1.143 -0.5588)
			(end 1.143 -0.5588)
			(stroke
				(width 0.1)
				(type default)
			)
			(layer "B.SilkS")
		)
		(fp_rect
			(start -1.143 0.5588)
			(end 1.143 -0.5588)
			(stroke
				(width 0)
				(type default)
			)
			(fill no)
			(layer "B.CrtYd")
		)
		(fp_line
			(start 0.508 0.3048)
			(end -0.508 0.3048)
			(stroke
				(width 0.1)
				(type default)
			)
			(layer "B.Fab")
		)
		(fp_line
			(start 0.508 -0.3048)
			(end 0.508 0.3048)
			(stroke
				(width 0.1)
				(type default)
			)
			(layer "B.Fab")
		)
		(fp_line
			(start -0.508 0.3048)
			(end -0.508 -0.3048)
			(stroke
				(width 0.1)
				(type default)
			)
			(layer "B.Fab")
		)
		(fp_line
			(start -0.508 -0.3048)
			(end 0.508 -0.3048)
			(stroke
				(width 0.1)
				(type default)
			)
			(layer "B.Fab")
		)
		(pad "1" smd rect
			(at 0.5334 0)
			(size 0.7112 0.6096)
			(layers "B.Cu" "B.Mask" "B.Paste")
			(net "XP1R0V_SW")
		)
		(pad "2" smd rect
			(at -0.5334 0)
			(size 0.7112 0.6096)
			(layers "B.Cu" "B.Mask" "B.Paste")
			(net "UNNAMED_523_CAPACITOR_I31_2")
		)
		(zone
			(layer "B.Cu")
			(hatch none 0.5)
			(connect_pads
				(clearance 0)
			)
			(min_thickness 0.25)
			(keepout
				(tracks allowed)
				(vias not_allowed)
				(pads allowed)
				(copperpour not_allowed)
				(footprints allowed)
			)
			(placement
				(enabled no)
				(sheetname "")
			)
			(fill
				(thermal_gap 0.5)
				(thermal_bridge_width 0.5)
				(island_removal_mode 0)
			)
			(polygon
				(pts
					(xy 142.5702 -50.5968) (xy 142.4178 -50.5968) (xy 142.4178 -49.9872) (xy 142.5702 -49.9872)
				)
			)
		)
	)
	(footprint ""
		(layer "B.Cu")
		(at 55.88 -16.129 -90)
		(property "Reference" "C290"
			(at -4.064 -0.59563 270)
			(unlocked yes)
			(layer "B.SilkS")
			(effects
				(font
					(size 0.7874 0.5842)
					(thickness 0.1524)
				)
				(justify mirror)
			)
		)
		(property "Value" "VAL*"
			(at -0.0762 2.067306 270)
			(unlocked yes)
			(layer "B.Fab")
			(hide yes)
			(effects
				(font
					(size 0.7874 0.5842)
					(thickness 0.1524)
				)
				(justify mirror)
			)
		)
		(property "Device Type" "CAPACITOR-G105-0B104-EK,0.1UF,A"
			(at -0.0508 1.127506 270)
			(unlocked yes)
			(layer "B.Fab")
			(hide yes)
			(effects
				(font
					(size 0.7874 0.5842)
					(thickness 0.1524)
				)
				(justify mirror)
			)
		)
		(property "User Part Number" "PARTNUM*"
			(at -0.1016 4.023106 270)
			(unlocked yes)
			(layer "Cmts.User")
			(hide yes)
			(effects
				(font
					(size 0.7874 0.5842)
					(thickness 0.1524)
				)
				(justify mirror)
			)
		)
		(property "Tolerance" "TOL*"
			(at -0.0762 3.032506 270)
			(unlocked yes)
			(layer "Cmts.User")
			(hide yes)
			(effects
				(font
					(size 0.7874 0.5842)
					(thickness 0.1524)
				)
				(justify mirror)
			)
		)
		(duplicate_pad_numbers_are_jumpers no)
		(fp_line
			(start -1.143 0.5588)
			(end -1.143 -0.5588)
			(stroke
				(width 0.1)
				(type default)
			)
			(layer "B.SilkS")
		)
		(fp_line
			(start 1.143 0.5588)
			(end -1.143 0.5588)
			(stroke
				(width 0.1)
				(type default)
			)
			(layer "B.SilkS")
		)
		(fp_line
			(start -1.143 -0.5588)
			(end 1.143 -0.5588)
			(stroke
				(width 0.1)
				(type default)
			)
			(layer "B.SilkS")
		)
		(fp_line
			(start 1.143 -0.5588)
			(end 1.143 0.5588)
			(stroke
				(width 0.1)
				(type default)
			)
			(layer "B.SilkS")
		)
		(fp_poly
			(pts
				(xy 1.143 0.5588) (xy -1.143 0.5588) (xy -1.143 -0.5588) (xy 1.143 -0.5588)
			)
			(stroke
				(width 0)
				(type default)
			)
			(fill no)
			(layer "B.CrtYd")
		)
		(fp_line
			(start -0.508 0.3048)
			(end -0.508 -0.3048)
			(stroke
				(width 0.1)
				(type default)
			)
			(layer "B.Fab")
		)
		(fp_line
			(start 0.508 0.3048)
			(end -0.508 0.3048)
			(stroke
				(width 0.1)
				(type default)
			)
			(layer "B.Fab")
		)
		(fp_line
			(start -0.508 -0.3048)
			(end 0.508 -0.3048)
			(stroke
				(width 0.1)
				(type default)
			)
			(layer "B.Fab")
		)
		(fp_line
			(start 0.508 -0.3048)
			(end 0.508 0.3048)
			(stroke
				(width 0.1)
				(type default)
			)
			(layer "B.Fab")
		)
		(pad "1" smd rect
			(at 0.5334 0 90)
			(size 0.7112 0.6096)
			(layers "B.Cu" "B.Mask" "B.Paste")
			(net "XP3R3V_PCIE")
		)
		(pad "2" smd rect
			(at -0.5334 0 90)
			(size 0.7112 0.6096)
			(layers "B.Cu" "B.Mask" "B.Paste")
			(net "SG")
		)
		(zone
			(layer "B.Cu")
			(hatch none 0.5)
			(connect_pads
				(clearance 0)
			)
			(min_thickness 0.25)
			(keepout
				(tracks allowed)
				(vias not_allowed)
				(pads allowed)
				(copperpour not_allowed)
				(footprints allowed)
			)
			(placement
				(enabled no)
				(sheetname "")
			)
			(fill
				(thermal_gap 0.5)
				(thermal_bridge_width 0.5)
				(island_removal_mode 0)
			)
			(polygon
				(pts
					(xy 55.5752 -16.0528) (xy 56.1848 -16.0528) (xy 56.1848 -16.2052) (xy 55.5752 -16.2052)
				)
			)
		)
		(zone
			(layer "B.Cu")
			(hatch none 0.5)
			(connect_pads
				(clearance 0)
			)
			(min_thickness 0.25)
			(keepout
				(tracks not_allowed)
				(vias allowed)
				(pads allowed)
				(copperpour not_allowed)
				(footprints allowed)
			)
			(placement
				(enabled no)
				(sheetname "")
			)
			(fill
				(thermal_gap 0.5)
				(thermal_bridge_width 0.5)
				(island_removal_mode 0)
			)
			(polygon
				(pts
					(xy 55.5752 -16.0528) (xy 56.1848 -16.0528) (xy 56.1848 -16.2052) (xy 55.5752 -16.2052)
				)
			)
		)
	)
	(footprint ""
		(layer "B.Cu")
		(at 21.0566 -42.7736)
		(property "Reference" "R58"
			(at -1.3716 -1.25603 0)
			(unlocked yes)
			(layer "B.SilkS")
			(effects
				(font
					(size 0.7874 0.5842)
					(thickness 0.1524)
				)
				(justify mirror)
			)
		)
		(property "Value" "VAL*"
			(at -0.02032 2.13233 0)
			(unlocked yes)
			(layer "B.Fab")
			(hide yes)
			(effects
				(font
					(size 0.7874 0.5842)
					(thickness 0.1524)
				)
				(justify mirror)
			)
		)
		(property "Device Type" "RESISTOR-G155-133R0-01,33OHM,1%"
			(at -0.008382 1.210564 0)
			(unlocked yes)
			(layer "B.Fab")
			(hide yes)
			(effects
				(font
					(size 0.7874 0.5842)
					(thickness 0.1524)
				)
				(justify mirror)
			)
		)
		(property "User Part Number" "PARTNUM*"
			(at -0.02032 4.024884 0)
			(unlocked yes)
			(layer "Cmts.User")
			(hide yes)
			(effects
				(font
					(size 0.7874 0.5842)
					(thickness 0.1524)
				)
				(justify mirror)
			)
		)
		(property "Tolerance" "TOL*"
			(at -0.044704 3.05435 0)
			(unlocked yes)
			(layer "Cmts.User")
			(hide yes)
			(effects
				(font
					(size 0.7874 0.5842)
					(thickness 0.1524)
				)
				(justify mirror)
			)
		)
		(duplicate_pad_numbers_are_jumpers no)
		(fp_line
			(start -1.143 -0.5588)
			(end 1.143 -0.5588)
			(stroke
				(width 0.1)
				(type default)
			)
			(layer "B.SilkS")
		)
		(fp_line
			(start -1.143 0.5588)
			(end -1.143 -0.5588)
			(stroke
				(width 0.1)
				(type default)
			)
			(layer "B.SilkS")
		)
		(fp_line
			(start 1.143 -0.5588)
			(end 1.143 0.5588)
			(stroke
				(width 0.1)
				(type default)
			)
			(layer "B.SilkS")
		)
		(fp_line
			(start 1.143 0.5588)
			(end -1.143 0.5588)
			(stroke
				(width 0.1)
				(type default)
			)
			(layer "B.SilkS")
		)
		(fp_rect
			(start 1.143 0.5588)
			(end -1.143 -0.5588)
			(stroke
				(width 0)
				(type default)
			)
			(fill no)
			(layer "B.CrtYd")
		)
		(fp_line
			(start -0.508 -0.3048)
			(end 0.508 -0.3048)
			(stroke
				(width 0.1)
				(type default)
			)
			(layer "B.Fab")
		)
		(fp_line
			(start -0.508 0.3048)
			(end -0.508 -0.3048)
			(stroke
				(width 0.1)
				(type default)
			)
			(layer "B.Fab")
		)
		(fp_line
			(start 0.508 -0.3048)
			(end 0.508 0.3048)
			(stroke
				(width 0.1)
				(type default)
			)
			(layer "B.Fab")
		)
		(fp_line
			(start 0.508 0.3048)
			(end -0.508 0.3048)
			(stroke
				(width 0.1)
				(type default)
			)
			(layer "B.Fab")
		)
		(pad "1" smd rect
			(at 0.5334 0 180)
			(size 0.7112 0.6096)
			(layers "B.Cu" "B.Mask" "B.Paste")
			(net "UNNAMED_5_CONNHDR2X2MSSMT_I126_")
		)
		(pad "2" smd rect
			(at -0.5334 0 180)
			(size 0.7112 0.6096)
			(layers "B.Cu" "B.Mask" "B.Paste")
			(net "R_PCA9546_I2C_SDA")
		)
		(zone
			(layer "B.Cu")
			(hatch none 0.5)
			(connect_pads
				(clearance 0)
			)
			(min_thickness 0.25)
			(keepout
				(tracks allowed)
				(vias not_allowed)
				(pads allowed)
				(copperpour not_allowed)
				(footprints allowed)
			)
			(placement
				(enabled no)
				(sheetname "")
			)
			(fill
				(thermal_gap 0.5)
				(thermal_bridge_width 0.5)
				(island_removal_mode 0)
			)
			(polygon
				(pts
					(xy 21.1328 -42.4688) (xy 21.1328 -43.0784) (xy 20.9804 -43.0784) (xy 20.9804 -42.4688)
				)
			)
		)
	)
	(footprint ""
		(layer "B.Cu")
		(at 115.166394 -44.577 180)
		(property "Reference" "C165"
			(at 43.030394 -1.93675 0)
			(unlocked yes)
			(layer "B.SilkS")
			(effects
				(font
					(size 0.635 0.4064)
					(thickness 0.1524)
				)
				(justify mirror)
			)
		)
		(property "Value" "VAL*"
			(at -0.0762 2.067306 180)
			(unlocked yes)
			(layer "B.Fab")
			(hide yes)
			(effects
				(font
					(size 0.7874 0.5842)
					(thickness 0.1524)
				)
				(justify mirror)
			)
		)
		(property "Device Type" "CAPACITOR-G105-0B104-CK,0.1UF,A"
			(at -0.0508 1.127506 180)
			(unlocked yes)
			(layer "B.Fab")
			(hide yes)
			(effects
				(font
					(size 0.7874 0.5842)
					(thickness 0.1524)
				)
				(justify mirror)
			)
		)
		(property "User Part Number" "PARTNUM*"
			(at -0.1016 4.023106 180)
			(unlocked yes)
			(layer "Cmts.User")
			(hide yes)
			(effects
				(font
					(size 0.7874 0.5842)
					(thickness 0.1524)
				)
				(justify mirror)
			)
		)
		(property "Tolerance" "TOL*"
			(at -0.0762 3.032506 180)
			(unlocked yes)
			(layer "Cmts.User")
			(hide yes)
			(effects
				(font
					(size 0.7874 0.5842)
					(thickness 0.1524)
				)
				(justify mirror)
			)
		)
		(duplicate_pad_numbers_are_jumpers no)
		(fp_line
			(start 1.143 0.5588)
			(end -1.143 0.5588)
			(stroke
				(width 0.1)
				(type default)
			)
			(layer "B.SilkS")
		)
		(fp_line
			(start 1.143 -0.5588)
			(end 1.143 0.5588)
			(stroke
				(width 0.1)
				(type default)
			)
			(layer "B.SilkS")
		)
		(fp_line
			(start -1.143 0.5588)
			(end -1.143 -0.5588)
			(stroke
				(width 0.1)
				(type default)
			)
			(layer "B.SilkS")
		)
		(fp_line
			(start -1.143 -0.5588)
			(end 1.143 -0.5588)
			(stroke
				(width 0.1)
				(type default)
			)
			(layer "B.SilkS")
		)
		(fp_rect
			(start 1.143 -0.5588)
			(end -1.143 0.5588)
			(stroke
				(width 0)
				(type default)
			)
			(fill no)
			(layer "B.CrtYd")
		)
		(fp_line
			(start 0.508 0.3048)
			(end -0.508 0.3048)
			(stroke
				(width 0.1)
				(type default)
			)
			(layer "B.Fab")
		)
		(fp_line
			(start 0.508 -0.3048)
			(end 0.508 0.3048)
			(stroke
				(width 0.1)
				(type default)
			)
			(layer "B.Fab")
		)
		(fp_line
			(start -0.508 0.3048)
			(end -0.508 -0.3048)
			(stroke
				(width 0.1)
				(type default)
			)
			(layer "B.Fab")
		)
		(fp_line
			(start -0.508 -0.3048)
			(end 0.508 -0.3048)
			(stroke
				(width 0.1)
				(type default)
			)
			(layer "B.Fab")
		)
		(pad "1" smd rect
			(at 0.5334 0)
			(size 0.7112 0.6096)
			(layers "B.Cu" "B.Mask" "B.Paste")
			(net "XP3R3V_FPGA")
		)
		(pad "2" smd rect
			(at -0.5334 0)
			(size 0.7112 0.6096)
			(layers "B.Cu" "B.Mask" "B.Paste")
			(net "SG")
		)
		(zone
			(layer "B.Cu")
			(hatch none 0.5)
			(connect_pads
				(clearance 0)
			)
			(min_thickness 0.25)
			(keepout
				(tracks allowed)
				(vias not_allowed)
				(pads allowed)
				(copperpour not_allowed)
				(footprints allowed)
			)
			(placement
				(enabled no)
				(sheetname "")
			)
			(fill
				(thermal_gap 0.5)
				(thermal_bridge_width 0.5)
				(island_removal_mode 0)
			)
			(polygon
				(pts
					(xy 115.090194 -44.2722) (xy 115.242594 -44.2722) (xy 115.242594 -44.8818) (xy 115.090194 -44.8818)
				)
			)
		)
	)
	(footprint ""
		(layer "B.Cu")
		(at 88.519 -85.598 180)
		(property "Reference" "R199"
			(at -0.254 5.42163 0)
			(unlocked yes)
			(layer "B.SilkS")
			(effects
				(font
					(size 0.7874 0.5842)
					(thickness 0.1524)
				)
				(justify mirror)
			)
		)
		(property "Value" "VAL*"
			(at -0.02032 2.13233 180)
			(unlocked yes)
			(layer "B.Fab")
			(hide yes)
			(effects
				(font
					(size 0.7874 0.5842)
					(thickness 0.1524)
				)
				(justify mirror)
			)
		)
		(property "Tolerance" "TOL*"
			(at -0.044704 3.05435 180)
			(unlocked yes)
			(layer "Cmts.User")
			(hide yes)
			(effects
				(font
					(size 0.7874 0.5842)
					(thickness 0.1524)
				)
				(justify mirror)
			)
		)
		(property "User Part Number" "PARTNUM*"
			(at -0.02032 4.024884 180)
			(unlocked yes)
			(layer "Cmts.User")
			(hide yes)
			(effects
				(font
					(size 0.7874 0.5842)
					(thickness 0.1524)
				)
				(justify mirror)
			)
		)
		(property "Device Type" "RESISTOR-G155-14701-01,4.7KOHMA"
			(at -0.008382 1.210564 180)
			(unlocked yes)
			(layer "B.Fab")
			(hide yes)
			(effects
				(font
					(size 0.7874 0.5842)
					(thickness 0.1524)
				)
				(justify mirror)
			)
		)
		(duplicate_pad_numbers_are_jumpers no)
		(fp_line
			(start 1.143 0.5588)
			(end -1.143 0.5588)
			(stroke
				(width 0.1)
				(type default)
			)
			(layer "B.SilkS")
		)
		(fp_line
			(start 1.143 -0.5588)
			(end 1.143 0.5588)
			(stroke
				(width 0.1)
				(type default)
			)
			(layer "B.SilkS")
		)
		(fp_line
			(start -1.143 0.5588)
			(end -1.143 -0.5588)
			(stroke
				(width 0.1)
				(type default)
			)
			(layer "B.SilkS")
		)
		(fp_line
			(start -1.143 -0.5588)
			(end 1.143 -0.5588)
			(stroke
				(width 0.1)
				(type default)
			)
			(layer "B.SilkS")
		)
		(fp_rect
			(start 1.143 -0.5588)
			(end -1.143 0.5588)
			(stroke
				(width 0)
				(type default)
			)
			(fill no)
			(layer "B.CrtYd")
		)
		(fp_line
			(start 0.508 0.3048)
			(end -0.508 0.3048)
			(stroke
				(width 0.1)
				(type default)
			)
			(layer "B.Fab")
		)
		(fp_line
			(start 0.508 -0.3048)
			(end 0.508 0.3048)
			(stroke
				(width 0.1)
				(type default)
			)
			(layer "B.Fab")
		)
		(fp_line
			(start -0.508 0.3048)
			(end -0.508 -0.3048)
			(stroke
				(width 0.1)
				(type default)
			)
			(layer "B.Fab")
		)
		(fp_line
			(start -0.508 -0.3048)
			(end 0.508 -0.3048)
			(stroke
				(width 0.1)
				(type default)
			)
			(layer "B.Fab")
		)
		(pad "1" smd rect
			(at 0.5334 0)
			(size 0.7112 0.6096)
			(layers "B.Cu" "B.Mask" "B.Paste")
			(net "UNNAMED_127_MT25QL128ABA1ESESOP")
		)
		(pad "2" smd rect
			(at -0.5334 0)
			(size 0.7112 0.6096)
			(layers "B.Cu" "B.Mask" "B.Paste")
			(net "XP3R3V_FPGA")
		)
		(zone
			(layer "B.Cu")
			(hatch none 0.5)
			(connect_pads
				(clearance 0)
			)
			(min_thickness 0.25)
			(keepout
				(tracks allowed)
				(vias not_allowed)
				(pads allowed)
				(copperpour not_allowed)
				(footprints allowed)
			)
			(placement
				(enabled no)
				(sheetname "")
			)
			(fill
				(thermal_gap 0.5)
				(thermal_bridge_width 0.5)
				(island_removal_mode 0)
			)
			(polygon
				(pts
					(xy 88.4428 -85.2932) (xy 88.5952 -85.2932) (xy 88.5952 -85.9028) (xy 88.4428 -85.9028)
				)
			)
		)
	)
)
